(kicad_pcb
	(version 20260206)
	(generator "pcbnew")
	(generator_version "10.0")
	(general
		(thickness 1.6)
		(legacy_teardrops no)
	)
	(paper "A4")
	(title_block
		(title "04192023_DAF0TMB3IC0_F0TG_MB_C_brd_V02_OCP.brd")
		(comment 1 "Grand Teton / footprints 3951-3954 of 8354")
	)
	(layers
		(0 "F.Cu" signal "TOP")
		(4 "In1.Cu" signal "GND")
		(6 "In2.Cu" signal "IN1")
		(8 "In3.Cu" signal "GND1")
		(10 "In4.Cu" signal "IN2")
		(12 "In5.Cu" signal "GND2")
		(14 "In6.Cu" signal "IN3")
		(16 "In7.Cu" signal "GND3")
		(18 "In8.Cu" signal "VCC")
		(20 "In9.Cu" signal "VCC1")
		(22 "In10.Cu" signal "GND4")
		(24 "In11.Cu" signal "IN4")
		(26 "In12.Cu" signal "GND5")
		(28 "In13.Cu" signal "IN5")
		(30 "In14.Cu" signal "GND6")
		(32 "In15.Cu" signal "IN6")
		(34 "In16.Cu" signal "GND7")
		(2 "B.Cu" signal "BOTTOM")
		(9 "F.Adhes" user "F.Adhesive")
		(11 "B.Adhes" user "B.Adhesive")
		(13 "F.Paste" user "Package Geometry/Pastemask Top")
		(15 "B.Paste" user "Package Geometry/Pastemask Bottom")
		(5 "F.SilkS" user "Ref Des/Silkscreen Top")
		(7 "B.SilkS" user "Ref Des/Silkscreen Bottom")
		(1 "F.Mask" user "Board Geometry/Soldermask Top")
		(3 "B.Mask" user "Board Geometry/Soldermask Bottom")
		(17 "Dwgs.User" user "User.Drawings")
		(19 "Cmts.User" user "User.Comments")
		(21 "Eco1.User" user "User.Eco1")
		(23 "Eco2.User" user "User.Eco2")
		(25 "Edge.Cuts" user "Board Geometry/Outline")
		(27 "Margin" user)
		(31 "F.CrtYd" user "Package Geometry/Place Bound Top")
		(29 "B.CrtYd" user "Package Geometry/Place Bound Bottom")
		(35 "F.Fab" user "Ref Des/Assembly Top")
		(33 "B.Fab" user "Ref Des/Assembly Bottom")
	)
	(footprint ""
		(layer "F.Cu")
		(at 10.873486 -92.687648 90)
		(property "Reference" "R3661"
			(at 0 0 90)
			(layer "F.SilkS")
			(hide yes)
			(effects
				(font
					(size 1.27 1.27)
				)
			)
		)
		(property "Value" ""
			(at 0 0 90)
			(layer "F.Fab")
			(effects
				(font
					(size 1.27 1.27)
				)
			)
		)
		(duplicate_pad_numbers_are_jumpers no)
		(fp_line
			(start 0.7874 -0.4064)
			(end 0.7874 0.4064)
			(stroke
				(width 0.1524)
				(type default)
			)
			(layer "F.SilkS")
		)
		(fp_line
			(start -0.7874 -0.4064)
			(end 0.7874 -0.4064)
			(stroke
				(width 0.1524)
				(type default)
			)
			(layer "F.SilkS")
		)
		(fp_line
			(start 0.7874 0.4064)
			(end -0.7874 0.4064)
			(stroke
				(width 0.1524)
				(type default)
			)
			(layer "F.SilkS")
		)
		(fp_line
			(start -0.7874 0.4064)
			(end -0.7874 -0.4064)
			(stroke
				(width 0.1524)
				(type default)
			)
			(layer "F.SilkS")
		)
		(fp_line
			(start -0.12065 -0.305054)
			(end -0.12065 -0.2794)
			(stroke
				(width 0.1)
				(type default)
			)
			(layer "F.Fab")
		)
		(fp_line
			(start -0.67945 -0.305054)
			(end -0.12065 -0.305054)
			(stroke
				(width 0.1)
				(type default)
			)
			(layer "F.Fab")
		)
		(fp_line
			(start 0.67945 -0.3048)
			(end 0.67945 0.3048)
			(stroke
				(width 0.1)
				(type default)
			)
			(layer "F.Fab")
		)
		(fp_line
			(start 0.12065 -0.3048)
			(end 0.67945 -0.3048)
			(stroke
				(width 0.1)
				(type default)
			)
			(layer "F.Fab")
		)
		(fp_line
			(start 0.12065 -0.2794)
			(end 0.12065 -0.3048)
			(stroke
				(width 0.1)
				(type default)
			)
			(layer "F.Fab")
		)
		(fp_line
			(start -0.12065 -0.2794)
			(end 0.12065 -0.2794)
			(stroke
				(width 0.1)
				(type default)
			)
			(layer "F.Fab")
		)
		(fp_line
			(start 0.120396 0.2794)
			(end -0.12065 0.2794)
			(stroke
				(width 0.1)
				(type default)
			)
			(layer "F.Fab")
		)
		(fp_line
			(start -0.12065 0.2794)
			(end -0.12065 0.3048)
			(stroke
				(width 0.1)
				(type default)
			)
			(layer "F.Fab")
		)
		(fp_line
			(start 0.67945 0.3048)
			(end 0.120396 0.3048)
			(stroke
				(width 0.1)
				(type default)
			)
			(layer "F.Fab")
		)
		(fp_line
			(start 0.120396 0.3048)
			(end 0.120396 0.2794)
			(stroke
				(width 0.1)
				(type default)
			)
			(layer "F.Fab")
		)
		(fp_line
			(start -0.12065 0.3048)
			(end -0.67945 0.3048)
			(stroke
				(width 0.1)
				(type default)
			)
			(layer "F.Fab")
		)
		(fp_line
			(start -0.67945 0.3048)
			(end -0.67945 -0.305054)
			(stroke
				(width 0.1)
				(type default)
			)
			(layer "F.Fab")
		)
		(pad "1" smd circle
			(at -0.40005 0 90)
			(size 0 0)
			(layers "F.Cu" "F.Mask" "F.Paste")
			(net "GND")
		)
		(pad "2" smd circle
			(at 0.40005 0 90)
			(size 0 0)
			(layers "F.Cu" "F.Mask" "F.Paste")
			(net "RST_USB_HUB_R_N")
		)
	)
	(footprint ""
		(layer "F.Cu")
		(at 346.046044 -381.41783 -90)
		(property "Reference" "C948"
			(at 0 0 270)
			(layer "F.SilkS")
			(hide yes)
			(effects
				(font
					(size 1.27 1.27)
				)
			)
		)
		(property "Value" ""
			(at 0 0 270)
			(layer "F.Fab")
			(effects
				(font
					(size 1.27 1.27)
				)
			)
		)
		(duplicate_pad_numbers_are_jumpers no)
		(fp_line
			(start -0.299974 0.150114)
			(end -0.299974 -0.150114)
			(stroke
				(width 0.1)
				(type default)
			)
			(layer "F.Fab")
		)
		(fp_line
			(start 0.299974 0.150114)
			(end -0.299974 0.150114)
			(stroke
				(width 0.1)
				(type default)
			)
			(layer "F.Fab")
		)
		(fp_line
			(start -0.299974 -0.150114)
			(end 0.299974 -0.150114)
			(stroke
				(width 0.1)
				(type default)
			)
			(layer "F.Fab")
		)
		(fp_line
			(start 0.299974 -0.150114)
			(end 0.299974 0.150114)
			(stroke
				(width 0.1)
				(type default)
			)
			(layer "F.Fab")
		)
		(pad "1" smd rect
			(at -0.2667 0 270)
			(size 0.3048 0.381)
			(layers "F.Cu" "F.Mask" "F.Paste")
			(net "P5E_CPU0_P1_TX_C_DN<8>")
		)
		(pad "2" smd rect
			(at 0.2667 0 270)
			(size 0.3048 0.381)
			(layers "F.Cu" "F.Mask" "F.Paste")
			(net "P5E_CPU0_P1_TX_DN<8>")
		)
	)
	(footprint ""
		(layer "F.Cu")
		(at 95.26143 -57.18683)
		(property "Reference" "PR3824"
			(at 0 0 0)
			(layer "F.SilkS")
			(hide yes)
			(effects
				(font
					(size 1.27 1.27)
				)
			)
		)
		(property "Value" ""
			(at 0 0 0)
			(layer "F.Fab")
			(effects
				(font
					(size 1.27 1.27)
				)
			)
		)
		(duplicate_pad_numbers_are_jumpers no)
		(fp_line
			(start -0.7874 -0.4064)
			(end 0.7874 -0.4064)
			(stroke
				(width 0.1524)
				(type default)
			)
			(layer "F.SilkS")
		)
		(fp_line
			(start -0.7874 0.4064)
			(end -0.7874 -0.4064)
			(stroke
				(width 0.1524)
				(type default)
			)
			(layer "F.SilkS")
		)
		(fp_line
			(start 0.7874 -0.4064)
			(end 0.7874 0.4064)
			(stroke
				(width 0.1524)
				(type default)
			)
			(layer "F.SilkS")
		)
		(fp_line
			(start 0.7874 0.4064)
			(end -0.7874 0.4064)
			(stroke
				(width 0.1524)
				(type default)
			)
			(layer "F.SilkS")
		)
		(fp_line
			(start -0.67945 -0.305054)
			(end -0.12065 -0.305054)
			(stroke
				(width 0.1)
				(type default)
			)
			(layer "F.Fab")
		)
		(fp_line
			(start -0.67945 0.3048)
			(end -0.67945 -0.305054)
			(stroke
				(width 0.1)
				(type default)
			)
			(layer "F.Fab")
		)
		(fp_line
			(start -0.12065 -0.305054)
			(end -0.12065 -0.2794)
			(stroke
				(width 0.1)
				(type default)
			)
			(layer "F.Fab")
		)
		(fp_line
			(start -0.12065 -0.2794)
			(end 0.12065 -0.2794)
			(stroke
				(width 0.1)
				(type default)
			)
			(layer "F.Fab")
		)
		(fp_line
			(start -0.12065 0.2794)
			(end -0.12065 0.3048)
			(stroke
				(width 0.1)
				(type default)
			)
			(layer "F.Fab")
		)
		(fp_line
			(start -0.12065 0.3048)
			(end -0.67945 0.3048)
			(stroke
				(width 0.1)
				(type default)
			)
			(layer "F.Fab")
		)
		(fp_line
			(start 0.120396 0.2794)
			(end -0.12065 0.2794)
			(stroke
				(width 0.1)
				(type default)
			)
			(layer "F.Fab")
		)
		(fp_line
			(start 0.120396 0.3048)
			(end 0.120396 0.2794)
			(stroke
				(width 0.1)
				(type default)
			)
			(layer "F.Fab")
		)
		(fp_line
			(start 0.12065 -0.3048)
			(end 0.67945 -0.3048)
			(stroke
				(width 0.1)
				(type default)
			)
			(layer "F.Fab")
		)
		(fp_line
			(start 0.12065 -0.2794)
			(end 0.12065 -0.3048)
			(stroke
				(width 0.1)
				(type default)
			)
			(layer "F.Fab")
		)
		(fp_line
			(start 0.67945 -0.3048)
			(end 0.67945 0.3048)
			(stroke
				(width 0.1)
				(type default)
			)
			(layer "F.Fab")
		)
		(fp_line
			(start 0.67945 0.3048)
			(end 0.120396 0.3048)
			(stroke
				(width 0.1)
				(type default)
			)
			(layer "F.Fab")
		)
		(pad "1" smd circle
			(at -0.40005 0)
			(size 0 0)
			(layers "F.Cu" "F.Mask" "F.Paste")
			(net "P3V3_OCP_SENSE_2")
		)
		(pad "2" smd circle
			(at 0.40005 0)
			(size 0 0)
			(layers "F.Cu" "F.Mask" "F.Paste")
			(net "GND")
		)
	)
	(footprint ""
		(layer "F.Cu")
		(at 104.816148 -382.27)
		(property "Reference" "R796"
			(at 0 0 0)
			(layer "F.SilkS")
			(hide yes)
			(effects
				(font
					(size 1.27 1.27)
				)
			)
		)
		(property "Value" ""
			(at 0 0 0)
			(layer "F.Fab")
			(effects
				(font
					(size 1.27 1.27)
				)
			)
		)
		(duplicate_pad_numbers_are_jumpers no)
		(fp_line
			(start -0.32512 -0.175006)
			(end 0.32512 -0.175006)
			(stroke
				(width 0.1)
				(type default)
			)
			(layer "F.Fab")
		)
		(fp_line
			(start -0.32512 0.175006)
			(end -0.32512 -0.175006)
			(stroke
				(width 0.1)
				(type default)
			)
			(layer "F.Fab")
		)
		(fp_line
			(start 0.32512 -0.175006)
			(end 0.32512 0.175006)
			(stroke
				(width 0.1)
				(type default)
			)
			(layer "F.Fab")
		)
		(fp_line
			(start 0.32512 0.175006)
			(end -0.32512 0.175006)
			(stroke
				(width 0.1)
				(type default)
			)
			(layer "F.Fab")
		)
		(pad "1" smd rect
			(at -0.2667 0)
			(size 0.3048 0.381)
			(layers "F.Cu" "F.Mask" "F.Paste")
			(net "RT_CPU1_P1_ADDR1")
		)
		(pad "2" smd rect
			(at 0.2667 0 180)
			(size 0.3048 0.381)
			(layers "F.Cu" "F.Mask" "F.Paste")
			(net "GND")
		)
	)
)
